# Kintex 410T devboard — KiCad project settings (.kicad_pro: net classes, design rules, text variables)
{
  "board": {
    "3dviewports": [],
    "design_settings": {
      "defaults": {
        "apply_defaults_to_fp_fields": false,
        "apply_defaults_to_fp_shapes": false,
        "apply_defaults_to_fp_text": false,
        "board_outline_line_width": 0.1,
        "copper_line_width": 0.2,
        "copper_text_italic": false,
        "copper_text_size_h": 1.5,
        "copper_text_size_v": 1.5,
        "copper_text_thickness": 0.3,
        "copper_text_upright": false,
        "courtyard_line_width": 0.05,
        "dimension_precision": 4,
        "dimension_units": 3,
        "dimensions": {
          "arrow_length": 1270000,
          "extension_offset": 500000,
          "keep_text_aligned": true,
          "suppress_zeroes": false,
          "text_position": 0,
          "units_format": 1
        },
        "fab_line_width": 0.1,
        "fab_text_italic": false,
        "fab_text_size_h": 1.0,
        "fab_text_size_v": 1.0,
        "fab_text_thickness": 0.15,
        "fab_text_upright": false,
        "other_line_width": 0.15,
        "other_text_italic": false,
        "other_text_size_h": 1.0,
        "other_text_size_v": 1.0,
        "other_text_thickness": 0.15,
        "other_text_upright": false,
        "pads": {
          "drill": 0.0,
          "height": 1.905,
          "width": 0.8096
        },
        "silk_line_width": 0.15,
        "silk_text_italic": false,
        "silk_text_size_h": 1.0,
        "silk_text_size_v": 1.0,
        "silk_text_thickness": 0.15,
        "silk_text_upright": false,
        "zones": {
          "45_degree_only": true,
          "min_clearance": 0.1
        }
      },
      "diff_pair_dimensions": [
        {
          "gap": 0.0,
          "via_gap": 0.0,
          "width": 0.0
        }
      ],
      "drc_exclusions": [],
      "meta": {
        "version": 2
      },
      "rule_severities": {
        "annular_width": "error",
        "clearance": "error",
        "connection_width": "warning",
        "copper_edge_clearance": "error",
        "copper_sliver": "warning",
        "courtyards_overlap": "ignore",
        "creepage": "error",
        "diff_pair_gap_out_of_range": "error",
        "diff_pair_uncoupled_length_too_long": "error",
        "drill_out_of_range": "error",
        "duplicate_footprints": "warning",
        "extra_footprint": "warning",
        "footprint": "error",
        "footprint_filters_mismatch": "ignore",
        "footprint_symbol_mismatch": "warning",
        "footprint_type_mismatch": "error",
        "hole_clearance": "error",
        "hole_near_hole": "error",
        "hole_to_hole": "error",
        "holes_co_located": "warning",
        "invalid_outline": "error",
        "isolated_copper": "warning",
        "item_on_disabled_layer": "error",
        "items_not_allowed": "error",
        "length_out_of_range": "error",
        "lib_footprint_issues": "ignore",
        "lib_footprint_mismatch": "warning",
        "malformed_courtyard": "error",
        "microvia_drill_out_of_range": "error",
        "mirrored_text_on_front_layer": "warning",
        "missing_courtyard": "ignore",
        "missing_footprint": "warning",
        "net_conflict": "warning",
        "nonmirrored_text_on_back_layer": "warning",
        "npth_inside_courtyard": "ignore",
        "padstack": "error",
        "pth_inside_courtyard": "ignore",
        "shorting_items": "error",
        "silk_edge_clearance": "warning",
        "silk_over_copper": "warning",
        "silk_overlap": "warning",
        "skew_out_of_range": "error",
        "solder_mask_bridge": "error",
        "starved_thermal": "error",
        "text_height": "warning",
        "text_on_edge_cuts": "error",
        "text_thickness": "warning",
        "through_hole_pad_without_hole": "error",
        "too_many_vias": "error",
        "track_angle": "error",
        "track_dangling": "error",
        "track_segment_length": "error",
        "track_width": "error",
        "tracks_crossing": "error",
        "unconnected_items": "error",
        "unresolved_variable": "error",
        "via_dangling": "error",
        "zones_intersect": "error"
      },
      "rules": {
        "allow_blind_buried_vias": false,
        "allow_microvias": false,
        "max_error": 0.005,
        "min_clearance": 0.1,
        "min_connection": 0.0,
        "min_copper_edge_clearance": 0.4,
        "min_groove_width": 0.0,
        "min_hole_clearance": 0.2,
        "min_hole_to_hole": 0.25,
        "min_microvia_diameter": 0.2,
        "min_microvia_drill": 0.1,
        "min_resolved_spokes": 1,
        "min_silk_clearance": 0.0,
        "min_text_height": 0.65,
        "min_text_thickness": 0.12,
        "min_through_hole_diameter": 0.2,
        "min_track_width": 0.1,
        "min_via_annular_width": 0.125,
        "min_via_diameter": 0.45,
        "solder_mask_clearance": 0.0,
        "solder_mask_min_width": 0.0,
        "solder_mask_to_copper_clearance": 0.0,
        "use_height_for_length_calcs": true
      },
      "teardrop_options": [
        {
          "td_onpthpad": true,
          "td_onroundshapesonly": false,
          "td_onsmdpad": true,
          "td_ontrackend": false,
          "td_onvia": true
        }
      ],
      "teardrop_parameters": [
        {
          "td_allow_use_two_tracks": true,
          "td_curve_segcount": 1,
          "td_height_ratio": 1.0,
          "td_length_ratio": 0.5,
          "td_maxheight": 2.0,
          "td_maxlen": 1.0,
          "td_on_pad_in_zone": false,
          "td_target_name": "td_round_shape",
          "td_width_to_size_filter_ratio": 0.9
        },
        {
          "td_allow_use_two_tracks": true,
          "td_curve_segcount": 1,
          "td_height_ratio": 1.0,
          "td_length_ratio": 0.5,
          "td_maxheight": 2.0,
          "td_maxlen": 1.0,
          "td_on_pad_in_zone": false,
          "td_target_name": "td_rect_shape",
          "td_width_to_size_filter_ratio": 0.9
        },
        {
          "td_allow_use_two_tracks": true,
          "td_curve_segcount": 1,
          "td_height_ratio": 1.0,
          "td_length_ratio": 0.5,
          "td_maxheight": 2.0,
          "td_maxlen": 1.0,
          "td_on_pad_in_zone": false,
          "td_target_name": "td_track_end",
          "td_width_to_size_filter_ratio": 0.9
        }
      ],
      "track_widths": [
        0.0,
        0.1,
        0.107,
        0.114,
        0.15,
        0.177,
        0.182,
        0.198,
        0.201,
        0.256,
        0.4,
        2.0
      ],
      "tuning_pattern_settings": {
        "diff_pair_defaults": {
          "corner_radius_percentage": 80,
          "corner_style": 1,
          "max_amplitude": 1.0,
          "min_amplitude": 0.2,
          "single_sided": false,
          "spacing": 1.0
        },
        "diff_pair_skew_defaults": {
          "corner_radius_percentage": 80,
          "corner_style": 1,
          "max_amplitude": 1.0,
          "min_amplitude": 0.2,
          "single_sided": false,
          "spacing": 0.6
        },
        "single_track_defaults": {
          "corner_radius_percentage": 80,
          "corner_style": 1,
          "max_amplitude": 1.0,
          "min_amplitude": 0.2,
          "single_sided": false,
          "spacing": 0.6
        }
      },
      "via_dimensions": [
        {
          "diameter": 0.0,
          "drill": 0.0
        },
        {
          "diameter": 0.45,
          "drill": 0.2
        }
      ],
      "zones_allow_external_fillets": false,
      "zones_use_no_outline": true
    },
    "ipc2581": {
      "dist": "",
      "distpn": "",
      "internal_id": "",
      "mfg": "",
      "mpn": ""
    },
    "layer_pairs": [],
    "layer_presets": [],
    "viewports": []
  },
  "boards": [],
  "cvpcb": {
    "equivalence_files": []
  },
  "erc": {
    "erc_exclusions": [],
    "meta": {
      "version": 0
    },
    "pin_map": [
      [
        0,
        0,
        0,
        0,
        0,
        0,
        1,
        0,
        0,
        0,
        0,
        2
      ],
      [
        0,
        2,
        0,
        1,
        0,
        0,
        1,
        0,
        2,
        2,
        2,
        2
      ],
      [
        0,
        0,
        0,
        0,
        0,
        0,
        1,
        0,
        1,
        0,
        1,
        2
      ],
      [
        0,
        1,
        0,
        0,
        0,
        0,
        1,
        1,
        2,
        1,
        1,
        2
      ],
      [
        0,
        0,
        0,
        0,
        0,
        0,
        1,
        0,
        0,
        0,
        0,
        2
      ],
      [
        0,
        0,
        0,
        0,
        0,
        0,
        0,
        0,
        0,
        0,
        0,
        2
      ],
      [
        1,
        1,
        1,
        1,
        1,
        0,
        1,
        1,
        1,
        1,
        1,
        2
      ],
      [
        0,
        0,
        0,
        1,
        0,
        0,
        1,
        0,
        0,
        0,
        0,
        2
      ],
      [
        0,
        2,
        1,
        2,
        0,
        0,
        1,
        0,
        2,
        2,
        2,
        2
      ],
      [
        0,
        2,
        0,
        1,
        0,
        0,
        1,
        0,
        2,
        0,
        0,
        2
      ],
      [
        0,
        2,
        1,
        1,
        0,
        0,
        1,
        0,
        2,
        0,
        0,
        2
      ],
      [
        2,
        2,
        2,
        2,
        2,
        2,
        2,
        2,
        2,
        2,
        2,
        2
      ]
    ],
    "rule_severities": {
      "bus_definition_conflict": "error",
      "bus_entry_needed": "error",
      "bus_to_bus_conflict": "error",
      "bus_to_net_conflict": "error",
      "conflicting_netclasses": "error",
      "different_unit_footprint": "error",
      "different_unit_net": "error",
      "duplicate_reference": "error",
      "duplicate_sheet_names": "error",
      "endpoint_off_grid": "warning",
      "extra_units": "error",
      "footprint_filter": "ignore",
      "footprint_link_issues": "warning",
      "four_way_junction": "ignore",
      "global_label_dangling": "warning",
      "hier_label_mismatch": "error",
      "label_dangling": "error",
      "label_multiple_wires": "warning",
      "lib_symbol_issues": "ignore",
      "lib_symbol_mismatch": "warning",
      "missing_bidi_pin": "warning",
      "missing_input_pin": "warning",
      "missing_power_pin": "error",
      "missing_unit": "warning",
      "multiple_net_names": "ignore",
      "net_not_bus_member": "warning",
      "no_connect_connected": "ignore",
      "no_connect_dangling": "warning",
      "pin_not_connected": "error",
      "pin_not_driven": "error",
      "pin_to_pin": "ignore",
      "power_pin_not_driven": "ignore",
      "same_local_global_label": "warning",
      "similar_label_and_power": "warning",
      "similar_labels": "warning",
      "similar_power": "warning",
      "simulation_model_issue": "ignore",
      "single_global_label": "ignore",
      "unannotated": "error",
      "unconnected_wire_endpoint": "warning",
      "unit_value_mismatch": "error",
      "unresolved_variable": "error",
      "wire_dangling": "error"
    }
  },
  "libraries": {
    "pinned_footprint_libs": [],
    "pinned_symbol_libs": []
  },
  "meta": {
    "filename": "k410t-devboard.kicad_pro",
    "version": 3
  },
  "net_settings": {
    "classes": [
      {
        "bus_width": 12,
        "clearance": 0.1,
        "diff_pair_gap": 0.1,
        "diff_pair_via_gap": 0.25,
        "diff_pair_width": 0.1,
        "line_style": 0,
        "microvia_diameter": 0.3,
        "microvia_drill": 0.1,
        "name": "Default",
        "pcb_color": "rgba(0, 0, 0, 0.000)",
        "priority": 2147483647,
        "schematic_color": "rgba(0, 0, 0, 0.000)",
        "track_width": 0.1,
        "via_diameter": 0.45,
        "via_drill": 0.2,
        "wire_width": 6
      },
      {
        "bus_width": 12,
        "clearance": 0.1,
        "diff_pair_gap": 0.1,
        "diff_pair_via_gap": 0.25,
        "diff_pair_width": 0.1,
        "line_style": 0,
        "microvia_diameter": 0.3,
        "microvia_drill": 0.1,
        "name": "100Ohm-diff",
        "pcb_color": "rgb(0, 0, 132)",
        "priority": 0,
        "schematic_color": "rgba(0, 0, 0, 0.000)",
        "track_width": 0.1,
        "via_diameter": 0.45,
        "via_drill": 0.2,
        "wire_width": 6
      },
      {
        "bus_width": 12,
        "clearance": 0.1,
        "diff_pair_gap": 0.1,
        "diff_pair_via_gap": 0.25,
        "diff_pair_width": 0.1,
        "line_style": 0,
        "microvia_diameter": 0.3,
        "microvia_drill": 0.1,
        "name": "40Ohm-se_DQ",
        "pcb_color": "rgb(0, 132, 0)",
        "priority": 1,
        "schematic_color": "rgba(0, 0, 0, 0.000)",
        "track_width": 0.1,
        "via_diameter": 0.45,
        "via_drill": 0.2,
        "wire_width": 6
      },
      {
        "bus_width": 12,
        "clearance": 0.1,
        "diff_pair_gap": 0.1,
        "diff_pair_via_gap": 0.25,
        "diff_pair_width": 0.1,
        "line_style": 0,
        "microvia_diameter": 0.3,
        "microvia_drill": 0.1,
        "name": "50Ohm-se",
        "pcb_color": "rgb(0, 132, 132)",
        "priority": 2,
        "schematic_color": "rgba(0, 0, 0, 0.000)",
        "track_width": 0.1,
        "via_diameter": 0.45,
        "via_drill": 0.2,
        "wire_width": 6
      },
      {
        "bus_width": 12,
        "clearance": 0.1,
        "diff_pair_gap": 0.1,
        "diff_pair_via_gap": 0.25,
        "diff_pair_width": 0.1,
        "line_style": 0,
        "microvia_diameter": 0.3,
        "microvia_drill": 0.1,
        "name": "80Ohm-diff_DQS",
        "pcb_color": "rgb(132, 0, 0)",
        "priority": 3,
        "schematic_color": "rgba(0, 0, 0, 0.000)",
        "track_width": 0.1,
        "via_diameter": 0.45,
        "via_drill": 0.2,
        "wire_width": 6
      },
      {
        "bus_width": 12,
        "clearance": 0.1,
        "diff_pair_gap": 0.1,
        "diff_pair_via_gap": 0.25,
        "diff_pair_width": 0.1,
        "line_style": 0,
        "microvia_diameter": 0.3,
        "microvia_drill": 0.1,
        "name": "85Ohm-diff_PCIe",
        "pcb_color": "rgb(132, 0, 132)",
        "priority": 4,
        "schematic_color": "rgba(0, 0, 0, 0.000)",
        "track_width": 0.1,
        "via_diameter": 0.45,
        "via_drill": 0.2,
        "wire_width": 6
      },
      {
        "bus_width": 12,
        "clearance": 0.1,
        "diff_pair_gap": 0.1,
        "diff_pair_via_gap": 0.25,
        "diff_pair_width": 0.1,
        "line_style": 0,
        "microvia_diameter": 0.3,
        "microvia_drill": 0.1,
        "name": "90Ohm-diff",
        "pcb_color": "rgba(0, 0, 0, 0.000)",
        "priority": 5,
        "schematic_color": "rgba(0, 0, 0, 0.000)",
        "track_width": 0.1,
        "via_diameter": 0.45,
        "via_drill": 0.2,
        "wire_width": 6
      },
      {
        "bus_width": 12,
        "clearance": 0.26,
        "diff_pair_gap": 0.1,
        "diff_pair_via_gap": 0.25,
        "diff_pair_width": 0.1,
        "line_style": 0,
        "microvia_diameter": 0.3,
        "microvia_drill": 0.1,
        "name": "POE",
        "pcb_color": "rgba(0, 0, 0, 0.000)",
        "priority": 6,
        "schematic_color": "rgba(0, 0, 0, 0.000)",
        "track_width": 0.1,
        "via_diameter": 0.45,
        "via_drill": 0.2,
        "wire_width": 6
      },
      {
        "bus_width": 12,
        "clearance": 0.1,
        "diff_pair_gap": 0.25,
        "diff_pair_via_gap": 0.25,
        "diff_pair_width": 0.2,
        "line_style": 0,
        "microvia_diameter": 0.3,
        "microvia_drill": 0.1,
        "name": "Supply",
        "pcb_color": "rgba(0, 0, 0, 0.000)",
        "priority": 7,
        "schematic_color": "rgba(0, 0, 0, 0.000)",
        "track_width": 0.4,
        "via_diameter": 0.45,
        "via_drill": 0.2,
        "wire_width": 6
      }
    ],
    "meta": {
      "version": 4
    },
    "net_colors": {
      "+0V675_VREF": "rgb(178, 215, 50)",
      "+0V675_VTT": "rgb(194, 20, 96)",
      "+1V0": "rgb(254, 39, 18)",
      "+1V0_MGTAVCC": "rgb(102, 176, 50)",
      "+1V2": "rgb(252, 96, 10)",
      "+1V2_MGTAVTT": "rgb(52, 124, 152)",
      "+1V35": "rgb(251, 153, 2)",
      "+1V8": "rgb(19, 233, 254)",
      "+3V3": "rgb(68, 36, 214)",
      "+5V": "rgb(254, 254, 51)",
      "GND": "rgb(78, 78, 78)",
      "VCC_USR_A": "rgb(252, 204, 26)",
      "VCC_USR_B": "rgb(0, 255, 128)"
    },
    "netclass_assignments": null,
    "netclass_patterns": [
      {
        "netclass": "100Ohm-diff",
        "pattern": "/FPGA Bank 17/HDMI.CLK_N"
      },
      {
        "netclass": "100Ohm-diff",
        "pattern": "/FPGA Bank 17/HDMI.CLK_P"
      },
      {
        "netclass": "100Ohm-diff",
        "pattern": "/FPGA Bank 17/HDMI.D0_N"
      },
      {
        "netclass": "100Ohm-diff",
        "pattern": "/FPGA Bank 17/HDMI.D0_P"
      },
      {
        "netclass": "100Ohm-diff",
        "pattern": "/FPGA Bank 17/HDMI.D1_N"
      },
      {
        "netclass": "100Ohm-diff",
        "pattern": "/FPGA Bank 17/HDMI.D1_P"
      },
      {
        "netclass": "100Ohm-diff",
        "pattern": "/FPGA Bank 17/HDMI.D2_N"
      },
      {
        "netclass": "100Ohm-diff",
        "pattern": "/FPGA Bank 17/HDMI.D2_P"
      },
      {
        "netclass": "100Ohm-diff",
        "pattern": "/FPGA Config/FPGA_CFG_DXN"
      },
      {
        "netclass": "100Ohm-diff",
        "pattern": "/FPGA Config/FPGA_CFG_DXP"
      },
      {
        "netclass": "100Ohm-diff",
        "pattern": "/HDMI + Ethernet/ETH1_N"
      },
      {
        "netclass": "100Ohm-diff",
        "pattern": "/HDMI + Ethernet/ETH1_P"
      },
      {
        "netclass": "100Ohm-diff",
        "pattern": "/HDMI + Ethernet/ETH2_N"
      },
      {
        "netclass": "100Ohm-diff",
        "pattern": "/HDMI + Ethernet/ETH2_P"
      },
      {
        "netclass": "100Ohm-diff",
        "pattern": "/HDMI + Ethernet/GBE1_N"
      },
      {
        "netclass": "100Ohm-diff",
        "pattern": "/HDMI + Ethernet/GBE1_P"
      },
      {
        "netclass": "100Ohm-diff",
        "pattern": "/HDMI + Ethernet/GBE2_N"
      },
      {
        "netclass": "100Ohm-diff",
        "pattern": "/HDMI + Ethernet/GBE2_P"
      },
      {
        "netclass": "100Ohm-diff",
        "pattern": "/HDMI + Ethernet/GBE3_N"
      },
      {
        "netclass": "100Ohm-diff",
        "pattern": "/HDMI + Ethernet/GBE3_P"
      },
      {
        "netclass": "100Ohm-diff",
        "pattern": "/HDMI + Ethernet/GBE4_N"
      },
      {
        "netclass": "100Ohm-diff",
        "pattern": "/HDMI + Ethernet/GBE4_P"
      },
      {
        "netclass": "100Ohm-diff",
        "pattern": "/HDMI + Ethernet/HDMI_CONN_CLK_N"
      },
      {
        "netclass": "100Ohm-diff",
        "pattern": "/HDMI + Ethernet/HDMI_CONN_CLK_P"
      },
      {
        "netclass": "100Ohm-diff",
        "pattern": "/HDMI + Ethernet/HDMI_CONN_D0_N"
      },
      {
        "netclass": "100Ohm-diff",
        "pattern": "/HDMI + Ethernet/HDMI_CONN_D0_P"
      },
      {
        "netclass": "100Ohm-diff",
        "pattern": "/HDMI + Ethernet/HDMI_CONN_D1_N"
      },
      {
        "netclass": "100Ohm-diff",
        "pattern": "/HDMI + Ethernet/HDMI_CONN_D1_P"
      },
      {
        "netclass": "100Ohm-diff",
        "pattern": "/HDMI + Ethernet/HDMI_CONN_D2_N"
      },
      {
        "netclass": "100Ohm-diff",
        "pattern": "/HDMI + Ethernet/HDMI_CONN_D2_P"
      },
      {
        "netclass": "40Ohm-se_DQ",
        "pattern": "/DRAM + SRAM/DDR.A0"
      },
      {
        "netclass": "40Ohm-se_DQ",
        "pattern": "/DRAM + SRAM/DDR.A1"
      },
      {
        "netclass": "40Ohm-se_DQ",
        "pattern": "/DRAM + SRAM/DDR.A10"
      },
      {
        "netclass": "40Ohm-se_DQ",
        "pattern": "/DRAM + SRAM/DDR.A11"
      },
      {
        "netclass": "40Ohm-se_DQ",
        "pattern": "/DRAM + SRAM/DDR.A12"
      },
      {
        "netclass": "40Ohm-se_DQ",
        "pattern": "/DRAM + SRAM/DDR.A13"
      },
      {
        "netclass": "40Ohm-se_DQ",
        "pattern": "/DRAM + SRAM/DDR.A14"
      },
      {
        "netclass": "40Ohm-se_DQ",
        "pattern": "/DRAM + SRAM/DDR.A15"
      },
      {
        "netclass": "40Ohm-se_DQ",
        "pattern": "/DRAM + SRAM/DDR.A2"
      },
      {
        "netclass": "40Ohm-se_DQ",
        "pattern": "/DRAM + SRAM/DDR.A3"
      },
      {
        "netclass": "40Ohm-se_DQ",
        "pattern": "/DRAM + SRAM/DDR.A4"
      },
      {
        "netclass": "40Ohm-se_DQ",
        "pattern": "/DRAM + SRAM/DDR.A5"
      },
      {
        "netclass": "40Ohm-se_DQ",
        "pattern": "/DRAM + SRAM/DDR.A6"
      },
      {
        "netclass": "40Ohm-se_DQ",
        "pattern": "/DRAM + SRAM/DDR.A7"
      },
      {
        "netclass": "40Ohm-se_DQ",
        "pattern": "/DRAM + SRAM/DDR.A8"
      },
      {
        "netclass": "40Ohm-se_DQ",
        "pattern": "/DRAM + SRAM/DDR.A9"
      },
      {
        "netclass": "40Ohm-se_DQ",
        "pattern": "/DRAM + SRAM/DDR.BA0"
      },
      {
        "netclass": "40Ohm-se_DQ",
        "pattern": "/DRAM + SRAM/DDR.BA1"
      },
      {
        "netclass": "40Ohm-se_DQ",
        "pattern": "/DRAM + SRAM/DDR.BA2"
      },
      {
        "netclass": "40Ohm-se_DQ",
        "pattern": "/DRAM + SRAM/DDR.CKE"
      },
      {
        "netclass": "40Ohm-se_DQ",
        "pattern": "/DRAM + SRAM/DDR.DM"
      },
      {
        "netclass": "40Ohm-se_DQ",
        "pattern": "/DRAM + SRAM/DDR.DQ0"
      },
      {
        "netclass": "40Ohm-se_DQ",
        "pattern": "/DRAM + SRAM/DDR.DQ1"
      },
      {
        "netclass": "40Ohm-se_DQ",
        "pattern": "/DRAM + SRAM/DDR.DQ2"
      },
      {
        "netclass": "40Ohm-se_DQ",
        "pattern": "/DRAM + SRAM/DDR.DQ3"
      },
      {
        "netclass": "40Ohm-se_DQ",
        "pattern": "/DRAM + SRAM/DDR.DQ4"
      },
      {
        "netclass": "40Ohm-se_DQ",
        "pattern": "/DRAM + SRAM/DDR.DQ5"
      },
      {
        "netclass": "40Ohm-se_DQ",
        "pattern": "/DRAM + SRAM/DDR.DQ6"
      },
      {
        "netclass": "40Ohm-se_DQ",
        "pattern": "/DRAM + SRAM/DDR.DQ7"
      },
      {
        "netclass": "40Ohm-se_DQ",
        "pattern": "/DRAM + SRAM/DDR.ODT"
      },
      {
        "netclass": "40Ohm-se_DQ",
        "pattern": "/DRAM + SRAM/DDR.~{CAS}"
      },
      {
        "netclass": "40Ohm-se_DQ",
        "pattern": "/DRAM + SRAM/DDR.~{CS}"
      },
      {
        "netclass": "40Ohm-se_DQ",
        "pattern": "/DRAM + SRAM/DDR.~{RAS}"
      },
      {
        "netclass": "40Ohm-se_DQ",
        "pattern": "/DRAM + SRAM/DDR.~{RESET}"
      },
      {
        "netclass": "40Ohm-se_DQ",
        "pattern": "/DRAM + SRAM/DDR.~{WE}"
      },
      {
        "netclass": "40Ohm-se_DQ",
        "pattern": "/DRAM + SRAM/DDR_ZQ"
      },
      {
        "netclass": "50Ohm-se",
        "pattern": "/Clocks/PLL_XI"
      },
      {
        "netclass": "50Ohm-se",
        "pattern": "/Clocks/PLL_XO"
      },
      {
        "netclass": "50Ohm-se",
        "pattern": "/Clocks/PLL_Y0"
      },
      {
        "netclass": "50Ohm-se",
        "pattern": "/Clocks/PLL_Y1"
      },
      {
        "netclass": "50Ohm-se",
        "pattern": "/Clocks/PLL_Y4"
      },
      {
        "netclass": "50Ohm-se",
        "pattern": "/DRAM + SRAM/SRAM.A0"
      },
      {
        "netclass": "50Ohm-se",
        "pattern": "/DRAM + SRAM/SRAM.A1"
      },
      {
        "netclass": "50Ohm-se",
        "pattern": "/DRAM + SRAM/SRAM.A10"
      },
      {
        "netclass": "50Ohm-se",
        "pattern": "/DRAM + SRAM/SRAM.A11"
      },
      {
        "netclass": "50Ohm-se",
        "pattern": "/DRAM + SRAM/SRAM.A12"
      },
      {
        "netclass": "50Ohm-se",
        "pattern": "/DRAM + SRAM/SRAM.A13"
      },
      {
        "netclass": "50Ohm-se",
        "pattern": "/DRAM + SRAM/SRAM.A14"
      },
      {
        "netclass": "50Ohm-se",
        "pattern": "/DRAM + SRAM/SRAM.A15"
      },
      {
        "netclass": "50Ohm-se",
        "pattern": "/DRAM + SRAM/SRAM.A16"
      },
      {
        "netclass": "50Ohm-se",
        "pattern": "/DRAM + SRAM/SRAM.A17"
      },
      {
        "netclass": "50Ohm-se",
        "pattern": "/DRAM + SRAM/SRAM.A18"
      },
      {
        "netclass": "50Ohm-se",
        "pattern": "/DRAM + SRAM/SRAM.A19"
      },
      {
        "netclass": "50Ohm-se",
        "pattern": "/DRAM + SRAM/SRAM.A2"
      },
      {
        "netclass": "50Ohm-se",
        "pattern": "/DRAM + SRAM/SRAM.A3"
      },
      {
        "netclass": "50Ohm-se",
        "pattern": "/DRAM + SRAM/SRAM.A4"
      },
      {
        "netclass": "50Ohm-se",
        "pattern": "/DRAM + SRAM/SRAM.A5"
      },
      {
        "netclass": "50Ohm-se",
        "pattern": "/DRAM + SRAM/SRAM.A6"
      },
      {
        "netclass": "50Ohm-se",
        "pattern": "/DRAM + SRAM/SRAM.A7"
      },
      {
        "netclass": "50Ohm-se",
        "pattern": "/DRAM + SRAM/SRAM.A8"
      },
      {
        "netclass": "50Ohm-se",
        "pattern": "/DRAM + SRAM/SRAM.A9"
      },
      {
        "netclass": "50Ohm-se",
        "pattern": "/DRAM + SRAM/SRAM.CE2"
      },
      {
        "netclass": "50Ohm-se",
        "pattern": "/DRAM + SRAM/SRAM.DQ0"
      },
      {
        "netclass": "50Ohm-se",
        "pattern": "/DRAM + SRAM/SRAM.DQ1"
      },
      {
        "netclass": "50Ohm-se",
        "pattern": "/DRAM + SRAM/SRAM.DQ2"
      },
      {
        "netclass": "50Ohm-se",
        "pattern": "/DRAM + SRAM/SRAM.DQ3"
      },
      {
        "netclass": "50Ohm-se",
        "pattern": "/DRAM + SRAM/SRAM.DQ4"
      },
      {
        "netclass": "50Ohm-se",
        "pattern": "/DRAM + SRAM/SRAM.DQ5"
      },
      {
        "netclass": "50Ohm-se",
        "pattern": "/DRAM + SRAM/SRAM.DQ6"
      },
      {
        "netclass": "50Ohm-se",
        "pattern": "/DRAM + SRAM/SRAM.DQ7"
      },
      {
        "netclass": "50Ohm-se",
        "pattern": "/DRAM + SRAM/SRAM.~{CE}"
      },
      {
        "netclass": "50Ohm-se",
        "pattern": "/DRAM + SRAM/SRAM.~{OE}"
      },
      {
        "netclass": "50Ohm-se",
        "pattern": "/DRAM + SRAM/SRAM.~{WE}"
      },
      {
        "netclass": "50Ohm-se",
        "pattern": "/FPGA Bank 17/GBE_RGMII.GTR_CLK"
      },
      {
        "netclass": "50Ohm-se",
        "pattern": "/FPGA Bank 17/GBE_RGMII.GTX_CLK"
      },
      {
        "netclass": "50Ohm-se",
        "pattern": "/FPGA Bank 17/GBE_RGMII.MDC"
      },
      {
        "netclass": "50Ohm-se",
        "pattern": "/FPGA Bank 17/GBE_RGMII.MDIO"
      },
      {
        "netclass": "50Ohm-se",
        "pattern": "/FPGA Bank 17/GBE_RGMII.REFCLK"
      },
      {
        "netclass": "50Ohm-se",
        "pattern": "/FPGA Bank 17/GBE_RGMII.RXD0"
      },
      {
        "netclass": "50Ohm-se",
        "pattern": "/FPGA Bank 17/GBE_RGMII.RXD1"
      },
      {
        "netclass": "50Ohm-se",
        "pattern": "/FPGA Bank 17/GBE_RGMII.RXD2"
      },
      {
        "netclass": "50Ohm-se",
        "pattern": "/FPGA Bank 17/GBE_RGMII.RXD3"
      },
      {
        "netclass": "50Ohm-se",
        "pattern": "/FPGA Bank 17/GBE_RGMII.RX_DV"
      },
      {
        "netclass": "50Ohm-se",
        "pattern": "/FPGA Bank 17/GBE_RGMII.TXD0"
      },
      {
        "netclass": "50Ohm-se",
        "pattern": "/FPGA Bank 17/GBE_RGMII.TXD1"
      },
      {
        "netclass": "50Ohm-se",
        "pattern": "/FPGA Bank 17/GBE_RGMII.TXD2"
      },
      {
        "netclass": "50Ohm-se",
        "pattern": "/FPGA Bank 17/GBE_RGMII.TXD3"
      },
      {
        "netclass": "50Ohm-se",
        "pattern": "/FPGA Bank 17/GBE_RGMII.TX_EN"
      },
      {
        "netclass": "50Ohm-se",
        "pattern": "/FPGA Bank 17/GBE_RGMII.~{INT}"
      },
      {
        "netclass": "50Ohm-se",
        "pattern": "/FPGA Bank 17/GBE_RGMII.~{RESET}"
      },
      {
        "netclass": "50Ohm-se",
        "pattern": "/FPGA Bank 32/ETH_RMII.MDC"
      },
      {
        "netclass": "50Ohm-se",
        "pattern": "/FPGA Bank 32/ETH_RMII.MDIO"
      },
      {
        "netclass": "50Ohm-se",
        "pattern": "/FPGA Bank 32/ETH_RMII.REFCLK"
      },
      {
        "netclass": "50Ohm-se",
        "pattern": "/FPGA Bank 32/ETH_RMII.RXD0"
      },
      {
        "netclass": "50Ohm-se",
        "pattern": "/FPGA Bank 32/ETH_RMII.RXD1"
      },
      {
        "netclass": "50Ohm-se",
        "pattern": "/FPGA Bank 32/ETH_RMII.RXER"
      },
      {
        "netclass": "50Ohm-se",
        "pattern": "/FPGA Bank 32/ETH_RMII.RX_DV"
      },
      {
        "netclass": "50Ohm-se",
        "pattern": "/FPGA Bank 32/ETH_RMII.TXD0"
      },
      {
        "netclass": "50Ohm-se",
        "pattern": "/FPGA Bank 32/ETH_RMII.TXD1"
      },
      {
        "netclass": "50Ohm-se",
        "pattern": "/FPGA Bank 32/ETH_RMII.TXEN"
      },
      {
        "netclass": "50Ohm-se",
        "pattern": "/FPGA Bank 32/ETH_RMII.~{RESET}"
      },
      {
        "netclass": "50Ohm-se",
        "pattern": "/FPGA Bank 33/SD_CARD.CLK"
      },
      {
        "netclass": "50Ohm-se",
        "pattern": "/FPGA Bank 33/SD_CARD.CMD"
      },
      {
        "netclass": "50Ohm-se",
        "pattern": "/FPGA Bank 33/SD_CARD.DAT0"
      },
      {
        "netclass": "50Ohm-se",
        "pattern": "/FPGA Bank 33/SD_CARD.DAT1"
      },
      {
        "netclass": "50Ohm-se",
        "pattern": "/FPGA Bank 33/SD_CARD.DAT2"
      },
      {
        "netclass": "50Ohm-se",
        "pattern": "/FPGA Bank 33/SD_CARD.DAT3"
      },
      {
        "netclass": "50Ohm-se",
        "pattern": "/FPGA Bank 33/SD_CARD.~{CD}"
      },
      {
        "netclass": "50Ohm-se",
        "pattern": "/FPGA Bank 33/USR_FLASH_0.CLK"
      },
      {
        "netclass": "50Ohm-se",
        "pattern": "/FPGA Bank 33/USR_FLASH_0.DQ0"
      },
      {
        "netclass": "50Ohm-se",
        "pattern": "/FPGA Bank 33/USR_FLASH_0.DQ1"
      },
      {
        "netclass": "50Ohm-se",
        "pattern": "/FPGA Bank 33/USR_FLASH_0.DQ2"
      },
      {
        "netclass": "50Ohm-se",
        "pattern": "/FPGA Bank 33/USR_FLASH_0.DQ3"
      },
      {
        "netclass": "50Ohm-se",
        "pattern": "/FPGA Bank 33/USR_FLASH_0.~{CS}"
      },
      {
        "netclass": "50Ohm-se",
        "pattern": "/HDMI + Ethernet/ETH_PHY_REFCLK"
      },
      {
        "netclass": "50Ohm-se",
        "pattern": "/HDMI + Ethernet/ETH_PHY_RXD1"
      },
      {
        "netclass": "50Ohm-se",
        "pattern": "/HDMI + Ethernet/ETH_PHY_RXDO"
      },
      {
        "netclass": "50Ohm-se",
        "pattern": "/HDMI + Ethernet/ETH_PHY_RXER"
      },
      {
        "netclass": "50Ohm-se",
        "pattern": "/HDMI + Ethernet/ETH_PHY_RX_DV"
      },
      {
        "netclass": "50Ohm-se",
        "pattern": "/HDMI + Ethernet/ETH_PHY_TXD1"
      },
      {
        "netclass": "50Ohm-se",
        "pattern": "/HDMI + Ethernet/ETH_PHY_TXDO"
      },
      {
        "netclass": "50Ohm-se",
        "pattern": "/HDMI + Ethernet/ETH_PHY_TXEN"
      },
      {
        "netclass": "50Ohm-se",
        "pattern": "/HDMI + Ethernet/ETH_XI"
      },
      {
        "netclass": "50Ohm-se",
        "pattern": "/HDMI + Ethernet/ETH_XO"
      },
      {
        "netclass": "50Ohm-se",
        "pattern": "/SPI Flash + SD Card/SD_CARD_~{CD}"
      },
      {
        "netclass": "50Ohm-se",
        "pattern": "/SPI Flash + SD Card/SYSTEM_FLASH_CLK"
      },
      {
        "netclass": "50Ohm-se",
        "pattern": "/SPI Flash + SD Card/SYSTEM_FLASH_DQ0"
      },
      {
        "netclass": "50Ohm-se",
        "pattern": "/SPI Flash + SD Card/SYSTEM_FLASH_DQ1"
      },
      {
        "netclass": "50Ohm-se",
        "pattern": "/SPI Flash + SD Card/SYSTEM_FLASH_DQ2"
      },
      {
        "netclass": "50Ohm-se",
        "pattern": "/SPI Flash + SD Card/SYSTEM_FLASH_DQ3"
      },
      {
        "netclass": "50Ohm-se",
        "pattern": "/SPI Flash + SD Card/SYSTEM_FLASH_~{CS}"
      },
      {
        "netclass": "50Ohm-se",
        "pattern": "/SPI Flash + SD Card/USR_FLASH_0_CLK"
      },
      {
        "netclass": "50Ohm-se",
        "pattern": "/SPI Flash + SD Card/USR_FLASH_0_DQ0"
      },
      {
        "netclass": "50Ohm-se",
        "pattern": "/SPI Flash + SD Card/USR_FLASH_0_DQ1"
      },
      {
        "netclass": "50Ohm-se",
        "pattern": "/SPI Flash + SD Card/USR_FLASH_0_DQ2"
      },
      {
        "netclass": "50Ohm-se",
        "pattern": "/SPI Flash + SD Card/USR_FLASH_0_DQ3"
      },
      {
        "netclass": "50Ohm-se",
        "pattern": "/SPI Flash + SD Card/USR_FLASH_0_~{CS}"
      },
      {
        "netclass": "50Ohm-se",
        "pattern": "/SPI Flash + SD Card/USR_FLASH_1_CLK"
      },
      {
        "netclass": "50Ohm-se",
        "pattern": "/SPI Flash + SD Card/USR_FLASH_1_DQ0"
      },
      {
        "netclass": "50Ohm-se",
        "pattern": "/SPI Flash + SD Card/USR_FLASH_1_DQ1"
      },
      {
        "netclass": "50Ohm-se",
        "pattern": "/SPI Flash + SD Card/USR_FLASH_1_DQ2"
      },
      {
        "netclass": "50Ohm-se",
        "pattern": "/SPI Flash + SD Card/USR_FLASH_1_DQ3"
      },
      {
        "netclass": "50Ohm-se",
        "pattern": "/SPI Flash + SD Card/USR_FLASH_1_~{CS}"
      },
      {
        "netclass": "80Ohm-diff_DQS",
        "pattern": "/DRAM + SRAM/DDR.CK_N"
      },
      {
        "netclass": "80Ohm-diff_DQS",
        "pattern": "/DRAM + SRAM/DDR.CK_P"
      },
      {
        "netclass": "80Ohm-diff_DQS",
        "pattern": "/DRAM + SRAM/DDR.DQS_N"
      },
      {
        "netclass": "80Ohm-diff_DQS",
        "pattern": "/DRAM + SRAM/DDR.DQS_P"
      },
      {
        "netclass": "85Ohm-diff_PCIe",
        "pattern": "/FMC+ HSPC/GTR_REFCLK0_R_N"
      },
      {
        "netclass": "85Ohm-diff_PCIe",
        "pattern": "/FMC+ HSPC/GTR_REFCLK0_R_P"
      },
      {
        "netclass": "85Ohm-diff_PCIe",
        "pattern": "/FMC+ HSPC/GTR_REFCLK1_R_N"
      },
      {
        "netclass": "85Ohm-diff_PCIe",
        "pattern": "/FMC+ HSPC/GTR_REFCLK1_R_P"
      },
      {
        "netclass": "85Ohm-diff_PCIe",
        "pattern": "/FMC+ HSPC/GTR_REFCLK2_R_N"
      },
      {
        "netclass": "85Ohm-diff_PCIe",
        "pattern": "/FMC+ HSPC/GTR_REFCLK2_R_P"
      },
      {
        "netclass": "85Ohm-diff_PCIe",
        "pattern": "/FMC+ HSPC/GTR_REFCLK3_R_N"
      },
      {
        "netclass": "85Ohm-diff_PCIe",
        "pattern": "/FMC+ HSPC/GTR_REFCLK3_R_P"
      },
      {
        "netclass": "85Ohm-diff_PCIe",
        "pattern": "/FMC+ HSPC/GTX115.REFCLK0_N"
      },
      {
        "netclass": "85Ohm-diff_PCIe",
        "pattern": "/FMC+ HSPC/GTX115.REFCLK0_P"
      },
      {
        "netclass": "85Ohm-diff_PCIe",
        "pattern": "/FMC+ HSPC/GTX115.REFCLK1_N"
      },
      {
        "netclass": "85Ohm-diff_PCIe",
        "pattern": "/FMC+ HSPC/GTX115.REFCLK1_P"
      },
      {
        "netclass": "85Ohm-diff_PCIe",
        "pattern": "/FMC+ HSPC/GTX115.RX0_N"
      },
      {
        "netclass": "85Ohm-diff_PCIe",
        "pattern": "/FMC+ HSPC/GTX115.RX0_P"
      },
      {
        "netclass": "85Ohm-diff_PCIe",
        "pattern": "/FMC+ HSPC/GTX115.RX1_N"
      },
      {
        "netclass": "85Ohm-diff_PCIe",
        "pattern": "/FMC+ HSPC/GTX115.RX1_P"
      },
      {
        "netclass": "85Ohm-diff_PCIe",
        "pattern": "/FMC+ HSPC/GTX115.RX2_N"
      },
      {
        "netclass": "85Ohm-diff_PCIe",
        "pattern": "/FMC+ HSPC/GTX115.RX2_P"
      },
      {
        "netclass": "85Ohm-diff_PCIe",
        "pattern": "/FMC+ HSPC/GTX115.RX3_N"
      },
      {
        "netclass": "85Ohm-diff_PCIe",
        "pattern": "/FMC+ HSPC/GTX115.RX3_P"
      },
      {
        "netclass": "85Ohm-diff_PCIe",
        "pattern": "/FMC+ HSPC/GTX115.TX0_N"
      },
      {
        "netclass": "85Ohm-diff_PCIe",
        "pattern": "/FMC+ HSPC/GTX115.TX0_P"
      },
      {
        "netclass": "85Ohm-diff_PCIe",
        "pattern": "/FMC+ HSPC/GTX115.TX1_N"
      },
      {
        "netclass": "85Ohm-diff_PCIe",
        "pattern": "/FMC+ HSPC/GTX115.TX1_P"
      },
      {
        "netclass": "85Ohm-diff_PCIe",
        "pattern": "/FMC+ HSPC/GTX115.TX2_N"
      },
      {
        "netclass": "85Ohm-diff_PCIe",
        "pattern": "/FMC+ HSPC/GTX115.TX2_P"
      },
      {
        "netclass": "85Ohm-diff_PCIe",
        "pattern": "/FMC+ HSPC/GTX115.TX3_N"
      },
      {
        "netclass": "85Ohm-diff_PCIe",
        "pattern": "/FMC+ HSPC/GTX115.TX3_P"
      },
      {
        "netclass": "85Ohm-diff_PCIe",
        "pattern": "/FMC+ HSPC/GTX116.REFCLK0_N"
      },
      {
        "netclass": "85Ohm-diff_PCIe",
        "pattern": "/FMC+ HSPC/GTX116.REFCLK0_P"
      },
      {
        "netclass": "85Ohm-diff_PCIe",
        "pattern": "/FMC+ HSPC/GTX116.REFCLK1_N"
      },
      {
        "netclass": "85Ohm-diff_PCIe",
        "pattern": "/FMC+ HSPC/GTX116.REFCLK1_P"
      },
      {
        "netclass": "85Ohm-diff_PCIe",
        "pattern": "/FMC+ HSPC/GTX116.RX0_N"
      },
      {
        "netclass": "85Ohm-diff_PCIe",
        "pattern": "/FMC+ HSPC/GTX116.RX0_P"
      },
      {
        "netclass": "85Ohm-diff_PCIe",
        "pattern": "/FMC+ HSPC/GTX116.RX1_N"
      },
      {
        "netclass": "85Ohm-diff_PCIe",
        "pattern": "/FMC+ HSPC/GTX116.RX1_P"
      },
      {
        "netclass": "85Ohm-diff_PCIe",
        "pattern": "/FMC+ HSPC/GTX116.RX2_N"
      },
      {
        "netclass": "85Ohm-diff_PCIe",
        "pattern": "/FMC+ HSPC/GTX116.RX2_P"
      },
      {
        "netclass": "85Ohm-diff_PCIe",
        "pattern": "/FMC+ HSPC/GTX116.RX3_N"
      },
      {
        "netclass": "85Ohm-diff_PCIe",
        "pattern": "/FMC+ HSPC/GTX116.RX3_P"
      },
      {
        "netclass": "85Ohm-diff_PCIe",
        "pattern": "/FMC+ HSPC/GTX116.TX0_N"
      },
      {
        "netclass": "85Ohm-diff_PCIe",
        "pattern": "/FMC+ HSPC/GTX116.TX0_P"
      },
      {
        "netclass": "85Ohm-diff_PCIe",
        "pattern": "/FMC+ HSPC/GTX116.TX1_N"
      },
      {
        "netclass": "85Ohm-diff_PCIe",
        "pattern": "/FMC+ HSPC/GTX116.TX1_P"
      },
      {
        "netclass": "85Ohm-diff_PCIe",
        "pattern": "/FMC+ HSPC/GTX116.TX2_N"
      },
      {
        "netclass": "85Ohm-diff_PCIe",
        "pattern": "/FMC+ HSPC/GTX116.TX2_P"
      },
      {
        "netclass": "85Ohm-diff_PCIe",
        "pattern": "/FMC+ HSPC/GTX116.TX3_N"
      },
      {
        "netclass": "85Ohm-diff_PCIe",
        "pattern": "/FMC+ HSPC/GTX116.TX3_P"
      },
      {
        "netclass": "85Ohm-diff_PCIe",
        "pattern": "/FMC+ HSPC/GTX_TX0_C_N"
      },
      {
        "netclass": "85Ohm-diff_PCIe",
        "pattern": "/FMC+ HSPC/GTX_TX0_C_P"
      },
      {
        "netclass": "85Ohm-diff_PCIe",
        "pattern": "/FMC+ HSPC/GTX_TX1_C_N"
      },
      {
        "netclass": "85Ohm-diff_PCIe",
        "pattern": "/FMC+ HSPC/GTX_TX1_C_P"
      },
      {
        "netclass": "85Ohm-diff_PCIe",
        "pattern": "/FMC+ HSPC/GTX_TX2_C_N"
      },
      {
        "netclass": "85Ohm-diff_PCIe",
        "pattern": "/FMC+ HSPC/GTX_TX2_C_P"
      },
      {
        "netclass": "85Ohm-diff_PCIe",
        "pattern": "/FMC+ HSPC/GTX_TX3_C_N"
      },
      {
        "netclass": "85Ohm-diff_PCIe",
        "pattern": "/FMC+ HSPC/GTX_TX3_C_P"
      },
      {
        "netclass": "85Ohm-diff_PCIe",
        "pattern": "/FMC+ HSPC/GTX_TX4_C_N"
      },
      {
        "netclass": "85Ohm-diff_PCIe",
        "pattern": "/FMC+ HSPC/GTX_TX4_C_P"
      },
      {
        "netclass": "85Ohm-diff_PCIe",
        "pattern": "/FMC+ HSPC/GTX_TX5_C_N"
      },
      {
        "netclass": "85Ohm-diff_PCIe",
        "pattern": "/FMC+ HSPC/GTX_TX5_C_P"
      },
      {
        "netclass": "85Ohm-diff_PCIe",
        "pattern": "/FMC+ HSPC/GTX_TX6_C_N"
      },
      {
        "netclass": "85Ohm-diff_PCIe",
        "pattern": "/FMC+ HSPC/GTX_TX6_C_P"
      },
      {
        "netclass": "85Ohm-diff_PCIe",
        "pattern": "/FMC+ HSPC/GTX_TX7_C_N"
      },
      {
        "netclass": "85Ohm-diff_PCIe",
        "pattern": "/FMC+ HSPC/GTX_TX7_C_P"
      },
      {
        "netclass": "90Ohm-diff",
        "pattern": "/FMC+ HSPC/FMC.IO0"
      },
      {
        "netclass": "90Ohm-diff",
        "pattern": "/FMC+ HSPC/FMC.IO10_N"
      },
      {
        "netclass": "90Ohm-diff",
        "pattern": "/FMC+ HSPC/FMC.IO10_P"
      },
      {
        "netclass": "90Ohm-diff",
        "pattern": "/FMC+ HSPC/FMC.IO11_N"
      },
      {
        "netclass": "90Ohm-diff",
        "pattern": "/FMC+ HSPC/FMC.IO11_P"
      },
      {
        "netclass": "90Ohm-diff",
        "pattern": "/FMC+ HSPC/FMC.IO12_N"
      },
      {
        "netclass": "90Ohm-diff",
        "pattern": "/FMC+ HSPC/FMC.IO12_P"
      },
      {
        "netclass": "90Ohm-diff",
        "pattern": "/FMC+ HSPC/FMC.IO13_N"
      },
      {
        "netclass": "90Ohm-diff",
        "pattern": "/FMC+ HSPC/FMC.IO13_P"
      },
      {
        "netclass": "90Ohm-diff",
        "pattern": "/FMC+ HSPC/FMC.IO14_N"
      },
      {
        "netclass": "90Ohm-diff",
        "pattern": "/FMC+ HSPC/FMC.IO14_P"
      },
      {
        "netclass": "90Ohm-diff",
        "pattern": "/FMC+ HSPC/FMC.IO15_N"
      },
      {
        "netclass": "90Ohm-diff",
        "pattern": "/FMC+ HSPC/FMC.IO15_P"
      },
      {
        "netclass": "90Ohm-diff",
        "pattern": "/FMC+ HSPC/FMC.IO16_N"
      },
      {
        "netclass": "90Ohm-diff",
        "pattern": "/FMC+ HSPC/FMC.IO16_P"
      },
      {
        "netclass": "90Ohm-diff",
        "pattern": "/FMC+ HSPC/FMC.IO17_N"
      },
      {
        "netclass": "90Ohm-diff",
        "pattern": "/FMC+ HSPC/FMC.IO17_P"
      },
      {
        "netclass": "90Ohm-diff",
        "pattern": "/FMC+ HSPC/FMC.IO18_N"
      },
      {
        "netclass": "90Ohm-diff",
        "pattern": "/FMC+ HSPC/FMC.IO18_P"
      },
      {
        "netclass": "90Ohm-diff",
        "pattern": "/FMC+ HSPC/FMC.IO19_N"
      },
      {
        "netclass": "90Ohm-diff",
        "pattern": "/FMC+ HSPC/FMC.IO19_P"
      },
      {
        "netclass": "90Ohm-diff",
        "pattern": "/FMC+ HSPC/FMC.IO1_N"
      },
      {
        "netclass": "90Ohm-diff",
        "pattern": "/FMC+ HSPC/FMC.IO1_P"
      },
      {
        "netclass": "90Ohm-diff",
        "pattern": "/FMC+ HSPC/FMC.IO20_N"
      },
      {
        "netclass": "90Ohm-diff",
        "pattern": "/FMC+ HSPC/FMC.IO20_P"
      },
      {
        "netclass": "90Ohm-diff",
        "pattern": "/FMC+ HSPC/FMC.IO21_N"
      },
      {
        "netclass": "90Ohm-diff",
        "pattern": "/FMC+ HSPC/FMC.IO21_P"
      },
      {
        "netclass": "90Ohm-diff",
        "pattern": "/FMC+ HSPC/FMC.IO22_N"
      },
      {
        "netclass": "90Ohm-diff",
        "pattern": "/FMC+ HSPC/FMC.IO22_P"
      },
      {
        "netclass": "90Ohm-diff",
        "pattern": "/FMC+ HSPC/FMC.IO23_N"
      },
      {
        "netclass": "90Ohm-diff",
        "pattern": "/FMC+ HSPC/FMC.IO23_P"
      },
      {
        "netclass": "90Ohm-diff",
        "pattern": "/FMC+ HSPC/FMC.IO24_N"
      },
      {
        "netclass": "90Ohm-diff",
        "pattern": "/FMC+ HSPC/FMC.IO24_P"
      },
      {
        "netclass": "90Ohm-diff",
        "pattern": "/FMC+ HSPC/FMC.IO25"
      },
      {
        "netclass": "90Ohm-diff",
        "pattern": "/FMC+ HSPC/FMC.IO2_N"
      },
      {
        "netclass": "90Ohm-diff",
        "pattern": "/FMC+ HSPC/FMC.IO2_P"
      },
      {
        "netclass": "90Ohm-diff",
        "pattern": "/FMC+ HSPC/FMC.IO3_N"
      },
      {
        "netclass": "90Ohm-diff",
        "pattern": "/FMC+ HSPC/FMC.IO3_P"
      },
      {
        "netclass": "90Ohm-diff",
        "pattern": "/FMC+ HSPC/FMC.IO4_N"
      },
      {
        "netclass": "90Ohm-diff",
        "pattern": "/FMC+ HSPC/FMC.IO4_P"
      },
      {
        "netclass": "90Ohm-diff",
        "pattern": "/FMC+ HSPC/FMC.IO5_N"
      },
      {
        "netclass": "90Ohm-diff",
        "pattern": "/FMC+ HSPC/FMC.IO5_P"
      },
      {
        "netclass": "90Ohm-diff",
        "pattern": "/FMC+ HSPC/FMC.IO6_N"
      },
      {
        "netclass": "90Ohm-diff",
        "pattern": "/FMC+ HSPC/FMC.IO6_P"
      },
      {
        "netclass": "90Ohm-diff",
        "pattern": "/FMC+ HSPC/FMC.IO7_N"
      },
      {
        "netclass": "90Ohm-diff",
        "pattern": "/FMC+ HSPC/FMC.IO7_P"
      },
      {
        "netclass": "90Ohm-diff",
        "pattern": "/FMC+ HSPC/FMC.IO8_N"
      },
      {
        "netclass": "90Ohm-diff",
        "pattern": "/FMC+ HSPC/FMC.IO8_P"
      },
      {
        "netclass": "90Ohm-diff",
        "pattern": "/FMC+ HSPC/FMC.IO9_N"
      },
      {
        "netclass": "90Ohm-diff",
        "pattern": "/FMC+ HSPC/FMC.IO9_P"
      },
      {
        "netclass": "90Ohm-diff",
        "pattern": "/USB PHY/USB_DBG_CONN_D+"
      },
      {
        "netclass": "90Ohm-diff",
        "pattern": "/USB PHY/USB_DBG_CONN_D-"
      },
      {
        "netclass": "90Ohm-diff",
        "pattern": "/USB PHY/USB_HOST_CONN_D+"
      },
      {
        "netclass": "90Ohm-diff",
        "pattern": "/USB PHY/USB_HOST_CONN_D-"
      },
      {
        "netclass": "90Ohm-diff",
        "pattern": "/USB PHY/USB_HOST_D+"
      },
      {
        "netclass": "90Ohm-diff",
        "pattern": "/USB PHY/USB_HOST_D-"
      },
      {
        "netclass": "90Ohm-diff",
        "pattern": "/USB PHY/USB_USR_CONN_D+"
      },
      {
        "netclass": "90Ohm-diff",
        "pattern": "/USB PHY/USB_USR_CONN_D-"
      },
      {
        "netclass": "90Ohm-diff",
        "pattern": "/USB PHY/USB_USR_D+"
      },
      {
        "netclass": "90Ohm-diff",
        "pattern": "/USB PHY/USB_USR_D-"
      },
      {
        "netclass": "POE",
        "pattern": "/HDMI + Ethernet/POE_ETH.VC1"
      },
      {
        "netclass": "POE",
        "pattern": "/HDMI + Ethernet/POE_ETH.VC2"
      },
      {
        "netclass": "POE",
        "pattern": "/HDMI + Ethernet/POE_ETH.VC3"
      },
      {
        "netclass": "POE",
        "pattern": "/HDMI + Ethernet/POE_ETH.VC4"
      },
      {
        "netclass": "POE",
        "pattern": "/HDMI + Ethernet/POE_GBE.VC1"
      },
      {
        "netclass": "POE",
        "pattern": "/HDMI + Ethernet/POE_GBE.VC2"
      },
      {
        "netclass": "POE",
        "pattern": "/HDMI + Ethernet/POE_GBE.VC3"
      },
      {
        "netclass": "POE",
        "pattern": "/HDMI + Ethernet/POE_GBE.VC4"
      },
      {
        "netclass": "Supply",
        "pattern": "+0V675_VREF"
      },
      {
        "netclass": "Supply",
        "pattern": "+0V675_VTT"
      },
      {
        "netclass": "Supply",
        "pattern": "+1V0"
      },
      {
        "netclass": "Supply",
        "pattern": "+1V0_MGTAVCC"
      },
      {
        "netclass": "Supply",
        "pattern": "+1V2"
      },
      {
        "netclass": "Supply",
        "pattern": "+1V2_MGTAVTT"
      },
      {
        "netclass": "Supply",
        "pattern": "+1V35"
      },
      {
        "netclass": "Supply",
        "pattern": "+1V8"
      },
      {
        "netclass": "Supply",
        "pattern": "+1V85_ADC"
      },
      {
        "netclass": "Supply",
        "pattern": "+3V3"
      },
      {
        "netclass": "Supply",
        "pattern": "+5V"
      },
      {
        "netclass": "Supply",
        "pattern": "/Power supply/PD_VBUS"
      },
      {
        "netclass": "Supply",
        "pattern": "/Power supply/USB_DBG_PD.VBUS"
      },
      {
        "netclass": "Supply",
        "pattern": "/Power supply/USB_PD_VBUS"
      },
      {
        "netclass": "Supply",
        "pattern": "/USB PHY/USB_HOST_VBUS"
      },
      {
        "netclass": "Supply",
        "pattern": "/USB PHY/USB_USR_VBUS"
      },
      {
        "netclass": "Supply",
        "pattern": "VCC_USR_A"
      },
      {
        "netclass": "Supply",
        "pattern": "VCC_USR_B"
      }
    ]
  },
  "pcbnew": {
    "last_paths": {
      "gencad": "",
      "idf": "",
      "netlist": "",
      "plot": "",
      "pos_files": "",
      "specctra_dsn": "",
      "step": "",
      "svg": "",
      "vrml": ""
    },
    "page_layout_descr_file": ""
  },
  "schematic": {
    "annotate_start_num": 0,
    "bom_export_filename": "${PROJECTNAME}.csv",
    "bom_fmt_presets": [],
    "bom_fmt_settings": {
      "field_delimiter": ",",
      "keep_line_breaks": false,
      "keep_tabs": false,
      "name": "CSV",
      "ref_delimiter": ",",
      "ref_range_delimiter": "",
      "string_delimiter": "\""
    },
    "bom_presets": [],
    "bom_settings": {
      "exclude_dnp": false,
      "fields_ordered": [
        {
          "group_by": false,
          "label": "Reference",
          "name": "Reference",
          "show": true
        },
        {
          "group_by": false,
          "label": "Qty",
          "name": "${QUANTITY}",
          "show": true
        },
        {
          "group_by": true,
          "label": "Value",
          "name": "Value",
          "show": true
        },
        {
          "group_by": true,
          "label": "DNP",
          "name": "${DNP}",
          "show": true
        },
        {
          "group_by": true,
          "label": "Exclude from BOM",
          "name": "${EXCLUDE_FROM_BOM}",
          "show": true
        },
        {
          "group_by": true,
          "label": "Exclude from Board",
          "name": "${EXCLUDE_FROM_BOARD}",
          "show": true
        },
        {
          "group_by": true,
          "label": "Footprint",
          "name": "Footprint",
          "show": true
        },
        {
          "group_by": false,
          "label": "Datasheet",
          "name": "Datasheet",
          "show": true
        }
      ],
      "filter_string": "",
      "group_symbols": true,
      "include_excluded_from_bom": true,
      "name": "Default Editing",
      "sort_asc": true,
      "sort_field": "Reference"
    },
    "connection_grid_size": 50.0,
    "drawing": {
      "dashed_lines_dash_length_ratio": 12.0,
      "dashed_lines_gap_length_ratio": 3.0,
      "default_line_thickness": 6.0,
      "default_text_size": 50.0,
      "field_names": [],
      "intersheets_ref_own_page": false,
      "intersheets_ref_prefix": "",
      "intersheets_ref_short": false,
      "intersheets_ref_show": false,
      "intersheets_ref_suffix": "",
      "junction_size_choice": 3,
      "label_size_ratio": 0.375,
      "operating_point_overlay_i_precision": 3,
      "operating_point_overlay_i_range": "~A",
      "operating_point_overlay_v_precision": 3,
      "operating_point_overlay_v_range": "~V",
      "overbar_offset_ratio": 1.23,
      "pin_symbol_size": 25.0,
      "text_offset_ratio": 0.15
    },
    "legacy_lib_dir": "",
    "legacy_lib_list": [],
    "meta": {
      "version": 1
    },
    "net_format_name": "",
    "ngspice": {
      "fix_include_paths": true,
      "fix_passive_vals": false,
      "meta": {
        "version": 0
      },
      "model_mode": 0,
      "workbook_filename": ""
    },
    "page_layout_descr_file": "",
    "plot_directory": "./",
    "space_save_all_events": true,
    "spice_adjust_passive_values": false,
    "spice_current_sheet_as_root": false,
    "spice_external_command": "spice \"%I\"",
    "spice_model_current_sheet_as_root": true,
    "spice_save_all_currents": false,
    "spice_save_all_dissipations": false,
    "spice_save_all_voltages": false,
    "subpart_first_id": 65,
    "subpart_id_separator": 0
  },
  "sheets": [
    [
      "",
      "Root"
    ],
    [
      "",
      "FPGA supply"
    ],
    [
      "",
      "FPGA Config"
    ],
    [
      "",
      "FPGA MGT Interface"
    ],
    [
      "",
      "DRAM + SRAM"
    ],
    [
      "",
      "Power supply"
    ],
    [
      "",
      "SPI Flash + SD Card"
    ],
    [
      "",
      "User GPIO + LED + button + DIP switch"
    ],
    [
      "",
      "USB PHY"
    ],
    [
      "",
      "HDMI + Ethernet"
    ],
    [
      "",
      "FMC+ HSPC"
    ],
    [
      "",
      "DC-DC Converters"
    ],
    [
      "",
      "Clocks"
    ],
    [
      "",
      "FPGA Bank 14 & 15"
    ],
    [
      "",
      "FPGA Bank 16 & 17"
    ],
    [
      "",
      "FPGA Bank 18 & 32"
    ],
    [
      "",
      "FPGA Bank 33 & 34"
    ],
    [
      "",
      "Supervisior MCU"
    ],
    [
      "",
      "FPGA Bank 12 & 13"
    ]
  ],
  "text_variables": {}
}
